(kicad_pcb
	(version 20260206)
	(generator "pcbnew")
	(generator_version "10.0")
	(general
		(thickness 1.6)
		(legacy_teardrops no)
	)
	(paper "A4")
	(title_block
		(title "netronome-mezz — pcbd0082-001_rev01_jul9_a.brd")
		(comment 1 "Open CloudServer (Microsoft) / footprints 246-253 of 714")
	)
	(layers
		(0 "F.Cu" signal "TOP")
		(4 "In1.Cu" signal "02_GND")
		(6 "In2.Cu" signal "03_SIG")
		(8 "In3.Cu" signal "04_SIG")
		(10 "In4.Cu" signal "05_GND")
		(12 "In5.Cu" signal "06_PWR1")
		(14 "In6.Cu" signal "07_SIG")
		(16 "In7.Cu" signal "08_SIG")
		(18 "In8.Cu" signal "09_GND")
		(2 "B.Cu" signal "BOTTOM")
		(9 "F.Adhes" user "F.Adhesive")
		(11 "B.Adhes" user "B.Adhesive")
		(13 "F.Paste" user "Package Geometry/Pastemask Top")
		(15 "B.Paste" user "Package Geometry/Pastemask Bottom")
		(5 "F.SilkS" user "Ref Des/Silkscreen Top")
		(7 "B.SilkS" user "Ref Des/Silkscreen Bottom")
		(1 "F.Mask" user "Board Geometry/Soldermask Top")
		(3 "B.Mask" user "Board Geometry/Soldermask Bottom")
		(17 "Dwgs.User" user "User.Drawings")
		(19 "Cmts.User" user "User.Comments")
		(21 "Eco1.User" user "User.Eco1")
		(23 "Eco2.User" user "User.Eco2")
		(25 "Edge.Cuts" user "Board Geometry/Outline")
		(27 "Margin" user)
		(31 "F.CrtYd" user "Package Geometry/Place Bound Top")
		(29 "B.CrtYd" user "Package Geometry/Place Bound Bottom")
		(35 "F.Fab" user "Ref Des/Assembly Top")
		(33 "B.Fab" user "Ref Des/Assembly Bottom")
		(45 "User.4" user "COMPVAL_TYPE_BOTTOM")
	)
	(footprint ""
		(layer "F.Cu")
		(at 83.82 35.306)
		(property "Reference" "TP60"
			(at -2.286 -1.37033 0)
			(unlocked yes)
			(layer "F.SilkS")
			(effects
				(font
					(size 0.7874 0.5842)
					(thickness 0.127)
				)
				(justify left)
			)
		)
		(property "Value" "*"
			(at -0.4826 -0.14732 0)
			(unlocked yes)
			(layer "F.Fab")
			(hide yes)
			(effects
				(font
					(size 1.27 0.9652)
					(thickness 0.000001)
				)
				(justify left)
			)
		)
		(property "Device Type" "TP_SMALL"
			(at -0.4826 -0.14732 0)
			(unlocked yes)
			(layer "F.Fab")
			(hide yes)
			(effects
				(font
					(size 1.27 0.9652)
					(thickness 0.000001)
				)
				(justify left)
			)
		)
		(duplicate_pad_numbers_are_jumpers no)
		(fp_line
			(start -0.8636 -0.8636)
			(end -0.8636 0.8636)
			(stroke
				(width 0.1524)
				(type default)
			)
			(layer "F.SilkS")
		)
		(fp_line
			(start -0.8636 0.8636)
			(end 0.8636 0.8636)
			(stroke
				(width 0.1524)
				(type default)
			)
			(layer "F.SilkS")
		)
		(fp_line
			(start 0.8636 -0.8636)
			(end -0.8636 -0.8636)
			(stroke
				(width 0.1524)
				(type default)
			)
			(layer "F.SilkS")
		)
		(fp_line
			(start 0.8636 0.8636)
			(end 0.8636 -0.8636)
			(stroke
				(width 0.1524)
				(type default)
			)
			(layer "F.SilkS")
		)
		(fp_poly
			(pts
				(xy -0.635 -0.635) (xy -0.635 0.635) (xy 0.635 0.635) (xy 0.635 -0.635)
			)
			(stroke
				(width 0)
				(type default)
			)
			(fill no)
			(layer "F.CrtYd")
		)
		(pad "1" smd rect
			(at 0 0)
			(size 1.27 1.27)
			(layers "F.Cu" "F.Mask" "F.Paste")
			(net "VDDQ_VTT_PGOOD")
		)
	)
	(footprint ""
		(layer "F.Cu")
		(at 80.391 44.069 -90)
		(property "Reference" "R127"
			(at 0 0 270)
			(layer "F.SilkS")
			(hide yes)
			(effects
				(font
					(size 1.27 1.27)
				)
			)
		)
		(property "Value" "10K"
			(at -0.148158 1.3462 0)
			(unlocked yes)
			(layer "F.Fab")
			(hide yes)
			(effects
				(font
					(size 1.27 0.9652)
					(thickness 0.000001)
				)
				(justify left)
			)
		)
		(property "Device Type" "REST0005"
			(at -0.148158 1.3462 0)
			(unlocked yes)
			(layer "F.Fab")
			(hide yes)
			(effects
				(font
					(size 1.27 0.9652)
					(thickness 0.000001)
				)
				(justify left)
			)
		)
		(duplicate_pad_numbers_are_jumpers no)
		(fp_poly
			(pts
				(xy 0.635 1.0668) (xy 0.635 -1.0668) (xy -0.635 -1.0668) (xy -0.635 1.0668)
			)
			(stroke
				(width 0)
				(type default)
			)
			(fill no)
			(layer "F.CrtYd")
		)
		(fp_line
			(start -0.254 0.508)
			(end -0.254 -0.508)
			(stroke
				(width 0.0254)
				(type default)
			)
			(layer "F.Fab")
		)
		(fp_line
			(start 0.254 0.508)
			(end -0.254 0.508)
			(stroke
				(width 0.0254)
				(type default)
			)
			(layer "F.Fab")
		)
		(fp_line
			(start -0.254 -0.508)
			(end 0.254 -0.508)
			(stroke
				(width 0.0254)
				(type default)
			)
			(layer "F.Fab")
		)
		(fp_line
			(start 0.254 -0.508)
			(end 0.254 0.508)
			(stroke
				(width 0.0254)
				(type default)
			)
			(layer "F.Fab")
		)
		(pad "1" smd rect
			(at 0 -0.4191 270)
			(size 0.508 0.5334)
			(layers "F.Cu" "F.Mask" "F.Paste")
			(net "11N2146")
		)
		(pad "2" smd rect
			(at 0 0.4191 270)
			(size 0.508 0.5334)
			(layers "F.Cu" "F.Mask" "F.Paste")
			(net "11N2152")
		)
		(zone
			(layer "F.Cu")
			(hatch none 0.5)
			(connect_pads
				(clearance 0)
			)
			(min_thickness 0.25)
			(keepout
				(tracks not_allowed)
				(vias allowed)
				(pads allowed)
				(copperpour not_allowed)
				(footprints allowed)
			)
			(placement
				(enabled no)
				(sheetname "")
			)
			(fill
				(thermal_gap 0.5)
				(thermal_bridge_width 0.5)
				(island_removal_mode 0)
			)
			(polygon
				(pts
					(xy 80.4164 44.0944) (xy 80.3656 44.0944) (xy 80.3656 44.0436) (xy 80.4164 44.0436)
				)
			)
		)
	)
	(footprint ""
		(layer "F.Cu")
		(at 74.3712 28.575)
		(property "Reference" "C105"
			(at 0 0 0)
			(layer "F.SilkS")
			(hide yes)
			(effects
				(font
					(size 1.27 1.27)
				)
			)
		)
		(property "Value" "0.1UF"
			(at -0.091846 0.2921 90)
			(unlocked yes)
			(layer "F.Fab")
			(hide yes)
			(effects
				(font
					(size 0.7874 0.5842)
					(thickness 0.2032)
				)
				(justify left)
			)
		)
		(property "Device Type" "CAPC0073"
			(at -0.091846 0.2921 90)
			(unlocked yes)
			(layer "F.Fab")
			(hide yes)
			(effects
				(font
					(size 0.7874 0.5842)
					(thickness 0.2032)
				)
				(justify left)
			)
		)
		(duplicate_pad_numbers_are_jumpers no)
		(fp_poly
			(pts
				(xy 0.635 1.0668) (xy 0.635 -1.0668) (xy -0.635 -1.0668) (xy -0.635 1.0668)
			)
			(stroke
				(width 0)
				(type default)
			)
			(fill no)
			(layer "F.CrtYd")
		)
		(fp_line
			(start -0.254 -0.508)
			(end 0.254 -0.508)
			(stroke
				(width 0.0254)
				(type default)
			)
			(layer "F.Fab")
		)
		(fp_line
			(start -0.254 0.508)
			(end -0.254 -0.508)
			(stroke
				(width 0.0254)
				(type default)
			)
			(layer "F.Fab")
		)
		(fp_line
			(start 0.254 -0.508)
			(end 0.254 0.508)
			(stroke
				(width 0.0254)
				(type default)
			)
			(layer "F.Fab")
		)
		(fp_line
			(start 0.254 0.508)
			(end -0.254 0.508)
			(stroke
				(width 0.0254)
				(type default)
			)
			(layer "F.Fab")
		)
		(pad "1" smd rect
			(at 0 -0.4191)
			(size 0.508 0.5334)
			(layers "F.Cu" "F.Mask" "F.Paste")
			(net "6N4748")
		)
		(pad "2" smd rect
			(at 0 0.4191)
			(size 0.508 0.5334)
			(layers "F.Cu" "F.Mask" "F.Paste")
			(net "DDR_VDDQ")
		)
		(zone
			(layer "F.Cu")
			(hatch none 0.5)
			(connect_pads
				(clearance 0)
			)
			(min_thickness 0.25)
			(keepout
				(tracks not_allowed)
				(vias allowed)
				(pads allowed)
				(copperpour not_allowed)
				(footprints allowed)
			)
			(placement
				(enabled no)
				(sheetname "")
			)
			(fill
				(thermal_gap 0.5)
				(thermal_bridge_width 0.5)
				(island_removal_mode 0)
			)
			(polygon
				(pts
					(xy 74.3966 28.5496) (xy 74.3966 28.6004) (xy 74.3458 28.6004) (xy 74.3458 28.5496)
				)
			)
		)
	)
	(footprint ""
		(layer "F.Cu")
		(at 19.05 28.448 90)
		(property "Reference" "R68"
			(at 0 0 90)
			(layer "F.SilkS")
			(hide yes)
			(effects
				(font
					(size 1.27 1.27)
				)
			)
		)
		(property "Value" "4.75K"
			(at -0.148158 1.3462 180)
			(unlocked yes)
			(layer "F.Fab")
			(hide yes)
			(effects
				(font
					(size 1.27 0.9652)
					(thickness 0.000001)
				)
				(justify left)
			)
		)
		(property "Device Type" "REST4024"
			(at -0.148158 1.3462 180)
			(unlocked yes)
			(layer "F.Fab")
			(hide yes)
			(effects
				(font
					(size 1.27 0.9652)
					(thickness 0.000001)
				)
				(justify left)
			)
		)
		(duplicate_pad_numbers_are_jumpers no)
		(fp_poly
			(pts
				(xy 0.635 1.0668) (xy 0.635 -1.0668) (xy -0.635 -1.0668) (xy -0.635 1.0668)
			)
			(stroke
				(width 0)
				(type default)
			)
			(fill no)
			(layer "F.CrtYd")
		)
		(fp_line
			(start 0.254 -0.508)
			(end 0.254 0.508)
			(stroke
				(width 0.0254)
				(type default)
			)
			(layer "F.Fab")
		)
		(fp_line
			(start -0.254 -0.508)
			(end 0.254 -0.508)
			(stroke
				(width 0.0254)
				(type default)
			)
			(layer "F.Fab")
		)
		(fp_line
			(start 0.254 0.508)
			(end -0.254 0.508)
			(stroke
				(width 0.0254)
				(type default)
			)
			(layer "F.Fab")
		)
		(fp_line
			(start -0.254 0.508)
			(end -0.254 -0.508)
			(stroke
				(width 0.0254)
				(type default)
			)
			(layer "F.Fab")
		)
		(pad "1" smd rect
			(at 0 -0.4191 90)
			(size 0.508 0.5334)
			(layers "F.Cu" "F.Mask" "F.Paste")
			(net "VDD_3.3V")
		)
		(pad "2" smd rect
			(at 0 0.4191 90)
			(size 0.508 0.5334)
			(layers "F.Cu" "F.Mask" "F.Paste")
			(net "NFP_CPLD_PRGM_JTAG_TDI")
		)
		(zone
			(layer "F.Cu")
			(hatch none 0.5)
			(connect_pads
				(clearance 0)
			)
			(min_thickness 0.25)
			(keepout
				(tracks not_allowed)
				(vias allowed)
				(pads allowed)
				(copperpour not_allowed)
				(footprints allowed)
			)
			(placement
				(enabled no)
				(sheetname "")
			)
			(fill
				(thermal_gap 0.5)
				(thermal_bridge_width 0.5)
				(island_removal_mode 0)
			)
			(polygon
				(pts
					(xy 19.0246 28.4226) (xy 19.0754 28.4226) (xy 19.0754 28.4734) (xy 19.0246 28.4734)
				)
			)
		)
	)
	(footprint ""
		(layer "F.Cu")
		(at 82.804 26.924)
		(property "Reference" "R208"
			(at 0 0 0)
			(layer "F.SilkS")
			(hide yes)
			(effects
				(font
					(size 1.27 1.27)
				)
			)
		)
		(property "Value" "39.0"
			(at -0.148158 1.3462 90)
			(unlocked yes)
			(layer "F.Fab")
			(hide yes)
			(effects
				(font
					(size 1.27 0.9652)
					(thickness 0.000001)
				)
				(justify left)
			)
		)
		(property "Device Type" "REST0108"
			(at -0.148158 1.3462 90)
			(unlocked yes)
			(layer "F.Fab")
			(hide yes)
			(effects
				(font
					(size 1.27 0.9652)
					(thickness 0.000001)
				)
				(justify left)
			)
		)
		(duplicate_pad_numbers_are_jumpers no)
		(fp_poly
			(pts
				(xy 0.635 1.0668) (xy 0.635 -1.0668) (xy -0.635 -1.0668) (xy -0.635 1.0668)
			)
			(stroke
				(width 0)
				(type default)
			)
			(fill no)
			(layer "F.CrtYd")
		)
		(fp_line
			(start -0.254 -0.508)
			(end 0.254 -0.508)
			(stroke
				(width 0.0254)
				(type default)
			)
			(layer "F.Fab")
		)
		(fp_line
			(start -0.254 0.508)
			(end -0.254 -0.508)
			(stroke
				(width 0.0254)
				(type default)
			)
			(layer "F.Fab")
		)
		(fp_line
			(start 0.254 -0.508)
			(end 0.254 0.508)
			(stroke
				(width 0.0254)
				(type default)
			)
			(layer "F.Fab")
		)
		(fp_line
			(start 0.254 0.508)
			(end -0.254 0.508)
			(stroke
				(width 0.0254)
				(type default)
			)
			(layer "F.Fab")
		)
		(pad "1" smd rect
			(at 0 -0.4191)
			(size 0.508 0.5334)
			(layers "F.Cu" "F.Mask" "F.Paste")
			(net "DDR0_32A_A2")
		)
		(pad "2" smd rect
			(at 0 0.4191)
			(size 0.508 0.5334)
			(layers "F.Cu" "F.Mask" "F.Paste")
			(net "DDR_VTT")
		)
		(zone
			(layer "F.Cu")
			(hatch none 0.5)
			(connect_pads
				(clearance 0)
			)
			(min_thickness 0.25)
			(keepout
				(tracks not_allowed)
				(vias allowed)
				(pads allowed)
				(copperpour not_allowed)
				(footprints allowed)
			)
			(placement
				(enabled no)
				(sheetname "")
			)
			(fill
				(thermal_gap 0.5)
				(thermal_bridge_width 0.5)
				(island_removal_mode 0)
			)
			(polygon
				(pts
					(xy 82.8294 26.8986) (xy 82.8294 26.9494) (xy 82.7786 26.9494) (xy 82.7786 26.8986)
				)
			)
		)
	)
	(footprint ""
		(layer "F.Cu")
		(at 78.8162 28.321 -90)
		(property "Reference" "C109"
			(at 0 0 270)
			(layer "F.SilkS")
			(hide yes)
			(effects
				(font
					(size 1.27 1.27)
				)
			)
		)
		(property "Value" "0.1UF"
			(at -0.091846 0.2921 0)
			(unlocked yes)
			(layer "F.Fab")
			(hide yes)
			(effects
				(font
					(size 0.7874 0.5842)
					(thickness 0.2032)
				)
				(justify left)
			)
		)
		(property "Device Type" "CAPC0073"
			(at -0.091846 0.2921 0)
			(unlocked yes)
			(layer "F.Fab")
			(hide yes)
			(effects
				(font
					(size 0.7874 0.5842)
					(thickness 0.2032)
				)
				(justify left)
			)
		)
		(duplicate_pad_numbers_are_jumpers no)
		(fp_poly
			(pts
				(xy 0.635 1.0668) (xy 0.635 -1.0668) (xy -0.635 -1.0668) (xy -0.635 1.0668)
			)
			(stroke
				(width 0)
				(type default)
			)
			(fill no)
			(layer "F.CrtYd")
		)
		(fp_line
			(start -0.254 0.508)
			(end -0.254 -0.508)
			(stroke
				(width 0.0254)
				(type default)
			)
			(layer "F.Fab")
		)
		(fp_line
			(start 0.254 0.508)
			(end -0.254 0.508)
			(stroke
				(width 0.0254)
				(type default)
			)
			(layer "F.Fab")
		)
		(fp_line
			(start -0.254 -0.508)
			(end 0.254 -0.508)
			(stroke
				(width 0.0254)
				(type default)
			)
			(layer "F.Fab")
		)
		(fp_line
			(start 0.254 -0.508)
			(end 0.254 0.508)
			(stroke
				(width 0.0254)
				(type default)
			)
			(layer "F.Fab")
		)
		(pad "1" smd rect
			(at 0 -0.4191 270)
			(size 0.508 0.5334)
			(layers "F.Cu" "F.Mask" "F.Paste")
			(net "DDR_VTT")
		)
		(pad "2" smd rect
			(at 0 0.4191 270)
			(size 0.508 0.5334)
			(layers "F.Cu" "F.Mask" "F.Paste")
			(net "GND")
		)
		(zone
			(layer "F.Cu")
			(hatch none 0.5)
			(connect_pads
				(clearance 0)
			)
			(min_thickness 0.25)
			(keepout
				(tracks not_allowed)
				(vias allowed)
				(pads allowed)
				(copperpour not_allowed)
				(footprints allowed)
			)
			(placement
				(enabled no)
				(sheetname "")
			)
			(fill
				(thermal_gap 0.5)
				(thermal_bridge_width 0.5)
				(island_removal_mode 0)
			)
			(polygon
				(pts
					(xy 78.8416 28.3464) (xy 78.7908 28.3464) (xy 78.7908 28.2956) (xy 78.8416 28.2956)
				)
			)
		)
	)
	(footprint ""
		(layer "F.Cu")
		(at 51.816 36.957 -90)
		(property "Reference" "R168"
			(at -0.86233 2.032 0)
			(unlocked yes)
			(layer "F.SilkS")
			(effects
				(font
					(size 0.7874 0.5842)
					(thickness 0.127)
				)
				(justify left)
			)
		)
		(property "Value" "0"
			(at -0.148158 1.3462 0)
			(unlocked yes)
			(layer "F.Fab")
			(hide yes)
			(effects
				(font
					(size 1.27 0.9652)
					(thickness 0.000001)
				)
				(justify left)
			)
		)
		(property "Device Type" "REST1111"
			(at -0.148158 1.3462 0)
			(unlocked yes)
			(layer "F.Fab")
			(hide yes)
			(effects
				(font
					(size 1.27 0.9652)
					(thickness 0.000001)
				)
				(justify left)
			)
		)
		(duplicate_pad_numbers_are_jumpers no)
		(fp_poly
			(pts
				(xy 0.635 1.0668) (xy 0.635 -1.0668) (xy -0.635 -1.0668) (xy -0.635 1.0668)
			)
			(stroke
				(width 0)
				(type default)
			)
			(fill no)
			(layer "F.CrtYd")
		)
		(fp_line
			(start -0.254 0.508)
			(end -0.254 -0.508)
			(stroke
				(width 0.0254)
				(type default)
			)
			(layer "F.Fab")
		)
		(fp_line
			(start 0.254 0.508)
			(end -0.254 0.508)
			(stroke
				(width 0.0254)
				(type default)
			)
			(layer "F.Fab")
		)
		(fp_line
			(start -0.254 -0.508)
			(end 0.254 -0.508)
			(stroke
				(width 0.0254)
				(type default)
			)
			(layer "F.Fab")
		)
		(fp_line
			(start 0.254 -0.508)
			(end 0.254 0.508)
			(stroke
				(width 0.0254)
				(type default)
			)
			(layer "F.Fab")
		)
		(pad "1" smd rect
			(at 0 -0.4191 270)
			(size 0.508 0.5334)
			(layers "F.Cu" "F.Mask" "F.Paste")
			(net "L_2_CORE_PHASE")
		)
		(pad "2" smd rect
			(at 0 0.4191 270)
			(size 0.508 0.5334)
			(layers "F.Cu" "F.Mask" "F.Paste")
			(net "NFP_VDD_CORE_ISEN2_P")
		)
		(zone
			(layer "F.Cu")
			(hatch none 0.5)
			(connect_pads
				(clearance 0)
			)
			(min_thickness 0.25)
			(keepout
				(tracks not_allowed)
				(vias allowed)
				(pads allowed)
				(copperpour not_allowed)
				(footprints allowed)
			)
			(placement
				(enabled no)
				(sheetname "")
			)
			(fill
				(thermal_gap 0.5)
				(thermal_bridge_width 0.5)
				(island_removal_mode 0)
			)
			(polygon
				(pts
					(xy 51.8414 36.9824) (xy 51.7906 36.9824) (xy 51.7906 36.9316) (xy 51.8414 36.9316)
				)
			)
		)
	)
	(footprint ""
		(layer "F.Cu")
		(at 33.274 2.286)
		(property "Reference" "R269"
			(at -1.24333 -0.889 90)
			(unlocked yes)
			(layer "F.SilkS")
			(effects
				(font
					(size 0.7874 0.5842)
					(thickness 0.127)
				)
				(justify left)
			)
		)
		(property "Value" "240"
			(at -0.148158 1.3462 90)
			(unlocked yes)
			(layer "F.Fab")
			(hide yes)
			(effects
				(font
					(size 1.27 0.9652)
					(thickness 0.000001)
				)
				(justify left)
			)
		)
		(property "Device Type" "REST0009"
			(at -0.148158 1.3462 90)
			(unlocked yes)
			(layer "F.Fab")
			(hide yes)
			(effects
				(font
					(size 1.27 0.9652)
					(thickness 0.000001)
				)
				(justify left)
			)
		)
		(duplicate_pad_numbers_are_jumpers no)
		(fp_poly
			(pts
				(xy 0.635 1.0668) (xy 0.635 -1.0668) (xy -0.635 -1.0668) (xy -0.635 1.0668)
			)
			(stroke
				(width 0)
				(type default)
			)
			(fill no)
			(layer "F.CrtYd")
		)
		(fp_line
			(start -0.254 -0.508)
			(end 0.254 -0.508)
			(stroke
				(width 0.0254)
				(type default)
			)
			(layer "F.Fab")
		)
		(fp_line
			(start -0.254 0.508)
			(end -0.254 -0.508)
			(stroke
				(width 0.0254)
				(type default)
			)
			(layer "F.Fab")
		)
		(fp_line
			(start 0.254 -0.508)
			(end 0.254 0.508)
			(stroke
				(width 0.0254)
				(type default)
			)
			(layer "F.Fab")
		)
		(fp_line
			(start 0.254 0.508)
			(end -0.254 0.508)
			(stroke
				(width 0.0254)
				(type default)
			)
			(layer "F.Fab")
		)
		(pad "1" smd rect
			(at 0 -0.4191)
			(size 0.508 0.5334)
			(layers "F.Cu" "F.Mask" "F.Paste")
			(net "NFP_REF_CLK_156M_EN")
		)
		(pad "2" smd rect
			(at 0 0.4191)
			(size 0.508 0.5334)
			(layers "F.Cu" "F.Mask" "F.Paste")
			(net "3N2285")
		)
		(zone
			(layer "F.Cu")
			(hatch none 0.5)
			(connect_pads
				(clearance 0)
			)
			(min_thickness 0.25)
			(keepout
				(tracks not_allowed)
				(vias allowed)
				(pads allowed)
				(copperpour not_allowed)
				(footprints allowed)
			)
			(placement
				(enabled no)
				(sheetname "")
			)
			(fill
				(thermal_gap 0.5)
				(thermal_bridge_width 0.5)
				(island_removal_mode 0)
			)
			(polygon
				(pts
					(xy 33.2994 2.2606) (xy 33.2994 2.3114) (xy 33.2486 2.3114) (xy 33.2486 2.2606)
				)
			)
		)
	)
)
